# S9S_MB_2U (Grand Teton) — schematic netlist excerpt (pin names and nets, part order shuffled) for the footprints in the layout excerpt that follows; sources: Cadence DE-HDL packaged netlist, KiCad conversion of 03242023_DA0F0TMBIJ0_F0T_Motherboard_J_brd_V01_OCP.brd

PC2209  Q_CAP  1UF 25V 10% EMPTY  pkg C0402  page 192 : A = P12V_E1S_VCC_0 ; B = GND
R3609  Q_RES  4.7K 1% EMPTY  pkg 0402LF  page 172 : A = GND ; B = INA230_3_A0

(kicad_pcb
	(version 20260206)
	(generator "pcbnew")
	(generator_version "10.0")
	(general
		(thickness 1.6)
		(legacy_teardrops no)
	)
	(paper "A4")
	(title_block
		(title "03242023_DA0F0TMBIJ0_F0T_Motherboard_J_brd_V01_OCP.brd")
		(comment 1 "Grand Teton / footprints 459-460 of 6105")
	)
	(layers
		(0 "F.Cu" signal "TOP")
		(4 "In1.Cu" signal "GND")
		(6 "In2.Cu" signal "IN1")
		(8 "In3.Cu" signal "GND1")
		(10 "In4.Cu" signal "IN2")
		(12 "In5.Cu" signal "GND2")
		(14 "In6.Cu" signal "IN3")
		(16 "In7.Cu" signal "GND3")
		(18 "In8.Cu" signal "VCC")
		(20 "In9.Cu" signal "VCC1")
		(22 "In10.Cu" signal "GND4")
		(24 "In11.Cu" signal "IN4")
		(26 "In12.Cu" signal "GND5")
		(28 "In13.Cu" signal "IN5")
		(30 "In14.Cu" signal "GND6")
		(32 "In15.Cu" signal "IN6")
		(34 "In16.Cu" signal "GND7")
		(2 "B.Cu" signal "BOTTOM")
		(9 "F.Adhes" user "F.Adhesive")
		(11 "B.Adhes" user "B.Adhesive")
		(13 "F.Paste" user "Package Geometry/Pastemask Top")
		(15 "B.Paste" user "Package Geometry/Pastemask Bottom")
		(5 "F.SilkS" user "Ref Des/Silkscreen Top")
		(7 "B.SilkS" user "Ref Des/Silkscreen Bottom")
		(1 "F.Mask" user "Board Geometry/Soldermask Top")
		(3 "B.Mask" user "Board Geometry/Soldermask Bottom")
		(17 "Dwgs.User" user "User.Drawings")
		(19 "Cmts.User" user "User.Comments")
		(21 "Eco1.User" user "User.Eco1")
		(23 "Eco2.User" user "User.Eco2")
		(25 "Edge.Cuts" user "Board Geometry/Outline")
		(27 "Margin" user)
		(31 "F.CrtYd" user "Package Geometry/Place Bound Top")
		(29 "B.CrtYd" user "Package Geometry/Place Bound Bottom")
		(35 "F.Fab" user "Ref Des/Assembly Top")
		(33 "B.Fab" user "Ref Des/Assembly Bottom")
	)
	(footprint ""
		(layer "F.Cu")
		(at 68.212462 -39.421562)
		(property "Reference" "R3609"
			(at 0 0 0)
			(layer "F.SilkS")
			(hide yes)
			(effects
				(font
					(size 1.27 1.27)
				)
			)
		)
		(property "Value" ""
			(at 0 0 0)
			(layer "F.Fab")
			(effects
				(font
					(size 1.27 1.27)
				)
			)
		)
		(duplicate_pad_numbers_are_jumpers no)
		(fp_line
			(start -0.7874 -0.4064)
			(end 0.7874 -0.4064)
			(stroke
				(width 0.1524)
				(type default)
			)
			(layer "F.SilkS")
		)
		(fp_line
			(start -0.7874 0.4064)
			(end -0.7874 -0.4064)
			(stroke
				(width 0.1524)
				(type default)
			)
			(layer "F.SilkS")
		)
		(fp_line
			(start 0.7874 -0.4064)
			(end 0.7874 0.4064)
			(stroke
				(width 0.1524)
				(type default)
			)
			(layer "F.SilkS")
		)
		(fp_line
			(start 0.7874 0.4064)
			(end -0.7874 0.4064)
			(stroke
				(width 0.1524)
				(type default)
			)
			(layer "F.SilkS")
		)
		(fp_line
			(start -0.67945 -0.305054)
			(end -0.12065 -0.305054)
			(stroke
				(width 0.1)
				(type default)
			)
			(layer "F.Fab")
		)
		(fp_line
			(start -0.67945 0.3048)
			(end -0.67945 -0.305054)
			(stroke
				(width 0.1)
				(type default)
			)
			(layer "F.Fab")
		)
		(fp_line
			(start -0.12065 -0.305054)
			(end -0.12065 -0.2794)
			(stroke
				(width 0.1)
				(type default)
			)
			(layer "F.Fab")
		)
		(fp_line
			(start -0.12065 -0.2794)
			(end 0.12065 -0.2794)
			(stroke
				(width 0.1)
				(type default)
			)
			(layer "F.Fab")
		)
		(fp_line
			(start -0.12065 0.2794)
			(end -0.12065 0.3048)
			(stroke
				(width 0.1)
				(type default)
			)
			(layer "F.Fab")
		)
		(fp_line
			(start -0.12065 0.3048)
			(end -0.67945 0.3048)
			(stroke
				(width 0.1)
				(type default)
			)
			(layer "F.Fab")
		)
		(fp_line
			(start 0.120396 0.2794)
			(end -0.12065 0.2794)
			(stroke
				(width 0.1)
				(type default)
			)
			(layer "F.Fab")
		)
		(fp_line
			(start 0.120396 0.3048)
			(end 0.120396 0.2794)
			(stroke
				(width 0.1)
				(type default)
			)
			(layer "F.Fab")
		)
		(fp_line
			(start 0.12065 -0.3048)
			(end 0.67945 -0.3048)
			(stroke
				(width 0.1)
				(type default)
			)
			(layer "F.Fab")
		)
		(fp_line
			(start 0.12065 -0.2794)
			(end 0.12065 -0.3048)
			(stroke
				(width 0.1)
				(type default)
			)
			(layer "F.Fab")
		)
		(fp_line
			(start 0.67945 -0.3048)
			(end 0.67945 0.3048)
			(stroke
				(width 0.1)
				(type default)
			)
			(layer "F.Fab")
		)
		(fp_line
			(start 0.67945 0.3048)
			(end 0.120396 0.3048)
			(stroke
				(width 0.1)
				(type default)
			)
			(layer "F.Fab")
		)
		(pad "1" smd circle
			(at -0.40005 0)
			(size 0 0)
			(layers "F.Cu" "F.Mask" "F.Paste")
			(net "GND")
		)
		(pad "2" smd circle
			(at 0.40005 0)
			(size 0 0)
			(layers "F.Cu" "F.Mask" "F.Paste")
			(net "INA230_3_A0")
		)
	)
	(footprint ""
		(layer "F.Cu")
		(at 255.447546 -42.886122 90)
		(property "Reference" "PC2209"
			(at 0 0 90)
			(layer "F.SilkS")
			(hide yes)
			(effects
				(font
					(size 1.27 1.27)
				)
			)
		)
		(property "Value" ""
			(at 0 0 90)
			(layer "F.Fab")
			(effects
				(font
					(size 1.27 1.27)
				)
			)
		)
		(duplicate_pad_numbers_are_jumpers no)
		(fp_line
			(start 0.7874 -0.4064)
			(end 0.7874 0.4064)
			(stroke
				(width 0.1524)
				(type default)
			)
			(layer "F.SilkS")
		)
		(fp_line
			(start -0.7874 -0.4064)
			(end 0.7874 -0.4064)
			(stroke
				(width 0.1524)
				(type default)
			)
			(layer "F.SilkS")
		)
		(fp_line
			(start 0.7874 0.4064)
			(end -0.7874 0.4064)
			(stroke
				(width 0.1524)
				(type default)
			)
			(layer "F.SilkS")
		)
		(fp_line
			(start -0.7874 0.4064)
			(end -0.7874 -0.4064)
			(stroke
				(width 0.1524)
				(type default)
			)
			(layer "F.SilkS")
		)
		(fp_line
			(start -0.12065 -0.305054)
			(end -0.12065 -0.2794)
			(stroke
				(width 0.1)
				(type default)
			)
			(layer "F.Fab")
		)
		(fp_line
			(start -0.67945 -0.305054)
			(end -0.12065 -0.305054)
			(stroke
				(width 0.1)
				(type default)
			)
			(layer "F.Fab")
		)
		(fp_line
			(start 0.67945 -0.3048)
			(end 0.67945 0.3048)
			(stroke
				(width 0.1)
				(type default)
			)
			(layer "F.Fab")
		)
		(fp_line
			(start 0.12065 -0.3048)
			(end 0.67945 -0.3048)
			(stroke
				(width 0.1)
				(type default)
			)
			(layer "F.Fab")
		)
		(fp_line
			(start 0.12065 -0.2794)
			(end 0.12065 -0.3048)
			(stroke
				(width 0.1)
				(type default)
			)
			(layer "F.Fab")
		)
		(fp_line
			(start -0.12065 -0.2794)
			(end 0.12065 -0.2794)
			(stroke
				(width 0.1)
				(type default)
			)
			(layer "F.Fab")
		)
		(fp_line
			(start 0.120396 0.2794)
			(end -0.12065 0.2794)
			(stroke
				(width 0.1)
				(type default)
			)
			(layer "F.Fab")
		)
		(fp_line
			(start -0.12065 0.2794)
			(end -0.12065 0.3048)
			(stroke
				(width 0.1)
				(type default)
			)
			(layer "F.Fab")
		)
		(fp_line
			(start 0.67945 0.3048)
			(end 0.120396 0.3048)
			(stroke
				(width 0.1)
				(type default)
			)
			(layer "F.Fab")
		)
		(fp_line
			(start 0.120396 0.3048)
			(end 0.120396 0.2794)
			(stroke
				(width 0.1)
				(type default)
			)
			(layer "F.Fab")
		)
		(fp_line
			(start -0.12065 0.3048)
			(end -0.67945 0.3048)
			(stroke
				(width 0.1)
				(type default)
			)
			(layer "F.Fab")
		)
		(fp_line
			(start -0.67945 0.3048)
			(end -0.67945 -0.305054)
			(stroke
				(width 0.1)
				(type default)
			)
			(layer "F.Fab")
		)
		(pad "1" smd circle
			(at -0.40005 0 90)
			(size 0 0)
			(layers "F.Cu" "F.Mask" "F.Paste")
			(net "P12V_E1S_VCC_0")
		)
		(pad "2" smd circle
			(at 0.40005 0 90)
			(size 0 0)
			(layers "F.Cu" "F.Mask" "F.Paste")
			(net "GND")
		)
	)
)
